#ISCELL
  mstr_misc dns *
  *
#ISCELL
  pure_quanta quanta_title_block_c *
  *
#ISCELL
  standard offpage *
  page200_i1
#ISCELL
  standard offpage *
  page200_i10
#CELL
  pure_quanta q_inductor *
  page200_i101
#ISCELL
  pure_quanta_power vcc_core *
  page200_i104
#CELL
  pure_quanta q_inductor *
  page200_i105
#CELL
  pure_quanta q_cap *
  page200_i107
#CELL
  pure_quanta q_res *
  page200_i110
#CELL
  pure_quanta q_res *
  page200_i111
#CELL
  pure_quanta q_capp *
  page200_i118
#CELL
  pure_quanta q_capp *
  page200_i119
#CELL
  pure_quanta q_capp *
  page200_i120
#CELL
  pure_quanta q_capp *
  page200_i121
#ISCELL
  pure_quanta_power vcc_core *
  page200_i122
#ISCELL
  pure_quanta_power universal_gnd *
  page200_i123
#CELL
  pure_quanta q_cap *
  page200_i124
#CELL
  pure_quanta q_cap *
  page200_i125
#CELL
  pure_quanta q_cap *
  page200_i126
#ISCELL
  pure_quanta_power universal_gnd *
  page200_i127
#ISCELL
  pure_quanta_power universal_gnd *
  page200_i128
#CELL
  pure_quanta q_res *
  page200_i129
#CELL
  pure_quanta q_cap *
  page200_i130
#ISCELL
  pure_quanta_power vcc_core *
  page200_i131
#CELL
  pure_quanta q_cap *
  page200_i132
#ISCELL
  pure_quanta_power universal_gnd *
  page200_i133
#ISCELL
  pure_quanta_power universal_gnd *
  page200_i134
#CELL
  pure_quanta q_res *
  page200_i135
#CELL
  pure_quanta q_cap *
  page200_i136
#CELL
  pure_quanta q_cap *
  page200_i138
#CELL
  pure_quanta q_cap *
  page200_i139
#ISCELL
  pure_quanta_power universal_gnd *
  page200_i140
#CELL
  pure_quanta q_res *
  page200_i141
#CELL
  pure_quanta q_cap *
  page200_i142
#ISCELL
  pure_quanta_power universal_gnd *
  page200_i143
#CELL
  pure_quanta q_res *
  page200_i144
#CELL
  pure_quanta q_cap *
  page200_i145
#CELL
  pure_quanta q_res *
  page200_i146
#ISCELL
  pure_quanta_power vcc_core *
  page200_i147
#CELL
  pure_quanta q_res *
  page200_i148
#ISCELL
  pure_quanta_power vcc_core *
  page200_i149
#CELL
  pure_quanta q_res *
  page200_i15
#ISCELL
  pure_quanta_power vcc_core *
  page200_i150
#CELL
  pure_quanta q_res *
  page200_i151
#CELL
  pure_quanta q_capp *
  page200_i152
#CELL
  pure_quanta q_capp *
  page200_i153
#CELL
  pure_quanta q_res *
  page200_i19
#ISCELL
  pure_quanta_power universal_gnd *
  page200_i2
#CELL
  pure_quanta q_cap *
  page200_i23
#CELL
  pure_quanta q_cap *
  page200_i24
#CELL
  pure_quanta q_cap *
  page200_i25
#CELL
  pure_quanta q_cap *
  page200_i26
#CELL
  pure_quanta q_capp *
  page200_i27
#CELL
  pure_quanta q_cap *
  page200_i29
#ISCELL
  standard offpage *
  page200_i3
#ISCELL
  pure_quanta_power universal_gnd *
  page200_i31
#CELL
  pure_quanta q_inductor *
  page200_i34
#ISCELL
  pure_quanta_power vcc_core *
  page200_i35
#CELL
  pure_quanta q_cap *
  page200_i37
#ISCELL
  pure_quanta_power universal_gnd *
  page200_i38
#CELL
  pure_quanta q_cap *
  page200_i39
#CELL
  pure_quanta q_cap *
  page200_i4
#ISCELL
  pure_quanta_power vcc_core *
  page200_i40
#CELL
  pure_quanta q_cap *
  page200_i43
#CELL
  pure_quanta isl99390frztr5935 *
  page200_i44
#ISCELL
  standard offpage *
  page200_i45
#ISCELL
  pure_quanta_power universal_gnd *
  page200_i46
#ISCELL
  standard offpage *
  page200_i47
#CELL
  pure_quanta q_cap *
  page200_i48
#ISCELL
  pure_quanta_power universal_gnd *
  page200_i49
#ISCELL
  pure_quanta_power universal_gnd *
  page200_i5
#ISCELL
  pure_quanta_power universal_gnd *
  page200_i50
#ISCELL
  standard offpage *
  page200_i51
#CELL
  pure_quanta q_res *
  page200_i52
#ISCELL
  standard offpage *
  page200_i55
#ISCELL
  pure_quanta_power universal_gnd *
  page200_i6
#CELL
  pure_quanta q_res *
  page200_i63
#CELL
  pure_quanta q_cap *
  page200_i66
#CELL
  pure_quanta q_cap *
  page200_i67
#CELL
  pure_quanta q_cap *
  page200_i69
#ISCELL
  standard offpage *
  page200_i7
#CELL
  pure_quanta q_cap *
  page200_i70
#ISCELL
  pure_quanta_power universal_gnd *
  page200_i71
#ISCELL
  pure_quanta_power vcc_core *
  page200_i73
#CELL
  pure_quanta q_cap *
  page200_i79
#ISCELL
  pure_quanta_power universal_gnd *
  page200_i80
#CELL
  pure_quanta q_cap *
  page200_i81
#ISCELL
  pure_quanta_power vcc_core *
  page200_i82
#CELL
  pure_quanta isl99390frztr5935 *
  page200_i84
#ISCELL
  pure_quanta_power universal_gnd *
  page200_i90
#ISCELL
  pure_quanta_power vcc_core *
  page200_i93
#CELL
  pure_quanta q_capp *
  page200_i98
